(kicad_pcb
	(version 20260206)
	(generator "pcbnew")
	(generator_version "10.0")
	(general
		(thickness 1.6)
		(legacy_teardrops no)
	)
	(paper "A4")
	(title_block
		(title "03242023_DA0F0TMBIJ0_F0T_Motherboard_J_brd_V01_OCP.brd")
		(comment 1 "Grand Teton / footprints 5557-5562 of 6105")
	)
	(layers
		(0 "F.Cu" signal "TOP")
		(4 "In1.Cu" signal "GND")
		(6 "In2.Cu" signal "IN1")
		(8 "In3.Cu" signal "GND1")
		(10 "In4.Cu" signal "IN2")
		(12 "In5.Cu" signal "GND2")
		(14 "In6.Cu" signal "IN3")
		(16 "In7.Cu" signal "GND3")
		(18 "In8.Cu" signal "VCC")
		(20 "In9.Cu" signal "VCC1")
		(22 "In10.Cu" signal "GND4")
		(24 "In11.Cu" signal "IN4")
		(26 "In12.Cu" signal "GND5")
		(28 "In13.Cu" signal "IN5")
		(30 "In14.Cu" signal "GND6")
		(32 "In15.Cu" signal "IN6")
		(34 "In16.Cu" signal "GND7")
		(2 "B.Cu" signal "BOTTOM")
		(9 "F.Adhes" user "F.Adhesive")
		(11 "B.Adhes" user "B.Adhesive")
		(13 "F.Paste" user "Package Geometry/Pastemask Top")
		(15 "B.Paste" user "Package Geometry/Pastemask Bottom")
		(5 "F.SilkS" user "Ref Des/Silkscreen Top")
		(7 "B.SilkS" user "Ref Des/Silkscreen Bottom")
		(1 "F.Mask" user "Board Geometry/Soldermask Top")
		(3 "B.Mask" user "Board Geometry/Soldermask Bottom")
		(17 "Dwgs.User" user "User.Drawings")
		(19 "Cmts.User" user "User.Comments")
		(21 "Eco1.User" user "User.Eco1")
		(23 "Eco2.User" user "User.Eco2")
		(25 "Edge.Cuts" user "Board Geometry/Outline")
		(27 "Margin" user)
		(31 "F.CrtYd" user "Package Geometry/Place Bound Top")
		(29 "B.CrtYd" user "Package Geometry/Place Bound Bottom")
		(35 "F.Fab" user "Ref Des/Assembly Top")
		(33 "B.Fab" user "Ref Des/Assembly Bottom")
	)
	(footprint ""
		(layer "B.Cu")
		(at 236.214666 -423.001948 90)
		(property "Reference" "R2802"
			(at 0 0 90)
			(layer "B.SilkS")
			(hide yes)
			(effects
				(font
					(size 1.27 1.27)
				)
				(justify mirror)
			)
		)
		(property "Value" ""
			(at 0 0 90)
			(layer "B.Fab")
			(effects
				(font
					(size 1.27 1.27)
				)
				(justify mirror)
			)
		)
		(duplicate_pad_numbers_are_jumpers no)
		(fp_line
			(start 0.7874 -0.4064)
			(end -0.7874 -0.4064)
			(stroke
				(width 0.1524)
				(type default)
			)
			(layer "B.SilkS")
		)
		(fp_line
			(start -0.7874 -0.4064)
			(end -0.7874 0.4064)
			(stroke
				(width 0.1524)
				(type default)
			)
			(layer "B.SilkS")
		)
		(fp_line
			(start 0.7874 0.4064)
			(end 0.7874 -0.4064)
			(stroke
				(width 0.1524)
				(type default)
			)
			(layer "B.SilkS")
		)
		(fp_line
			(start -0.7874 0.4064)
			(end 0.7874 0.4064)
			(stroke
				(width 0.1524)
				(type default)
			)
			(layer "B.SilkS")
		)
		(fp_line
			(start 0.67945 -0.305054)
			(end 0.12065 -0.305054)
			(stroke
				(width 0.1)
				(type default)
			)
			(layer "B.Fab")
		)
		(fp_line
			(start 0.12065 -0.305054)
			(end 0.12065 -0.2794)
			(stroke
				(width 0.1)
				(type default)
			)
			(layer "B.Fab")
		)
		(fp_line
			(start -0.12065 -0.3048)
			(end -0.67945 -0.3048)
			(stroke
				(width 0.1)
				(type default)
			)
			(layer "B.Fab")
		)
		(fp_line
			(start -0.67945 -0.3048)
			(end -0.67945 0.3048)
			(stroke
				(width 0.1)
				(type default)
			)
			(layer "B.Fab")
		)
		(fp_line
			(start 0.12065 -0.2794)
			(end -0.12065 -0.2794)
			(stroke
				(width 0.1)
				(type default)
			)
			(layer "B.Fab")
		)
		(fp_line
			(start -0.12065 -0.2794)
			(end -0.12065 -0.3048)
			(stroke
				(width 0.1)
				(type default)
			)
			(layer "B.Fab")
		)
		(fp_line
			(start 0.12065 0.2794)
			(end 0.12065 0.3048)
			(stroke
				(width 0.1)
				(type default)
			)
			(layer "B.Fab")
		)
		(fp_line
			(start -0.120396 0.2794)
			(end 0.12065 0.2794)
			(stroke
				(width 0.1)
				(type default)
			)
			(layer "B.Fab")
		)
		(fp_line
			(start 0.67945 0.3048)
			(end 0.67945 -0.305054)
			(stroke
				(width 0.1)
				(type default)
			)
			(layer "B.Fab")
		)
		(fp_line
			(start 0.12065 0.3048)
			(end 0.67945 0.3048)
			(stroke
				(width 0.1)
				(type default)
			)
			(layer "B.Fab")
		)
		(fp_line
			(start -0.120396 0.3048)
			(end -0.120396 0.2794)
			(stroke
				(width 0.1)
				(type default)
			)
			(layer "B.Fab")
		)
		(fp_line
			(start -0.67945 0.3048)
			(end -0.120396 0.3048)
			(stroke
				(width 0.1)
				(type default)
			)
			(layer "B.Fab")
		)
		(pad "1" smd circle
			(at 0.40005 0 270)
			(size 0 0)
			(layers "B.Cu" "B.Mask" "B.Paste")
			(net "HPDB_HSC_PWRGD_R")
		)
		(pad "2" smd circle
			(at -0.40005 0 270)
			(size 0 0)
			(layers "B.Cu" "B.Mask" "B.Paste")
			(net "HPDB_HSC_PWRGD")
		)
	)
	(footprint ""
		(layer "B.Cu")
		(at 336.878676 -330.214224 -90)
		(property "Reference" "PC2336"
			(at 0 0 90)
			(layer "B.SilkS")
			(hide yes)
			(effects
				(font
					(size 1.27 1.27)
				)
				(justify mirror)
			)
		)
		(property "Value" ""
			(at 0 0 90)
			(layer "B.Fab")
			(effects
				(font
					(size 1.27 1.27)
				)
				(justify mirror)
			)
		)
		(duplicate_pad_numbers_are_jumpers no)
		(fp_line
			(start -4.533392 2.249932)
			(end 4.533392 2.249932)
			(stroke
				(width 0.1524)
				(type default)
			)
			(layer "B.SilkS")
		)
		(fp_line
			(start 4.533392 2.249932)
			(end 4.533392 -2.249932)
			(stroke
				(width 0.1524)
				(type default)
			)
			(layer "B.SilkS")
		)
		(fp_line
			(start -4.533392 -2.249932)
			(end -4.533392 2.249932)
			(stroke
				(width 0.1524)
				(type default)
			)
			(layer "B.SilkS")
		)
		(fp_line
			(start 4.533392 -2.249932)
			(end -4.533392 -2.249932)
			(stroke
				(width 0.1524)
				(type default)
			)
			(layer "B.SilkS")
		)
		(fp_rect
			(start 5.39242 2.326132)
			(end 4.533392 -2.326132)
			(stroke
				(width 0)
				(type default)
			)
			(fill yes)
			(layer "B.SilkS")
		)
		(fp_line
			(start -3.750056 2.249932)
			(end 3.750056 2.249932)
			(stroke
				(width 0.1)
				(type default)
			)
			(layer "B.Fab")
		)
		(fp_line
			(start 3.750056 2.249932)
			(end 3.750056 -2.249932)
			(stroke
				(width 0.1)
				(type default)
			)
			(layer "B.Fab")
		)
		(fp_line
			(start -3.750056 -2.249932)
			(end -3.750056 2.249932)
			(stroke
				(width 0.1)
				(type default)
			)
			(layer "B.Fab")
		)
		(fp_line
			(start 3.750056 -2.249932)
			(end -3.750056 -2.249932)
			(stroke
				(width 0.1)
				(type default)
			)
			(layer "B.Fab")
		)
		(fp_text user "-"
			(at -4.619244 1.269746 270)
			(unlocked yes)
			(layer "B.SilkS")
			(effects
				(font
					(size 1.905 1.4224)
					(thickness 0.1524)
				)
				(justify left mirror)
			)
		)
		(fp_text user "+"
			(at 6.322314 0.786384 180)
			(unlocked yes)
			(layer "B.SilkS")
			(effects
				(font
					(size 1.905 1.4224)
					(thickness 0.1524)
				)
				(justify left mirror)
			)
		)
		(fp_text user "+"
			(at 6.322314 0.786384 180)
			(unlocked yes)
			(layer "B.Fab")
			(effects
				(font
					(size 1.905 1.4224)
					(thickness 0.1524)
				)
				(justify left mirror)
			)
		)
		(fp_text user "-"
			(at -4.8514 -0.14605 270)
			(unlocked yes)
			(layer "B.Fab")
			(effects
				(font
					(size 1.905 1.4224)
					(thickness 0.1524)
				)
				(justify left mirror)
			)
		)
		(pad "1" smd rect
			(at 3.199892 0 90)
			(size 2.413 2.8194)
			(layers "B.Cu" "B.Mask" "B.Paste")
			(net "PVCCIN_CPU0")
		)
		(pad "2" smd rect
			(at -3.199892 0 90)
			(size 2.413 2.8194)
			(layers "B.Cu" "B.Mask" "B.Paste")
			(net "GND")
		)
	)
	(footprint ""
		(layer "B.Cu")
		(at 236.89056 -249.037348)
		(property "Reference" "C2257"
			(at 0 0 0)
			(layer "B.SilkS")
			(hide yes)
			(effects
				(font
					(size 1.27 1.27)
				)
				(justify mirror)
			)
		)
		(property "Value" ""
			(at 0 0 0)
			(layer "B.Fab")
			(effects
				(font
					(size 1.27 1.27)
				)
				(justify mirror)
			)
		)
		(duplicate_pad_numbers_are_jumpers no)
		(fp_line
			(start -0.7874 -0.4064)
			(end -0.7874 0.4064)
			(stroke
				(width 0.1524)
				(type default)
			)
			(layer "B.SilkS")
		)
		(fp_line
			(start -0.7874 0.4064)
			(end 0.7874 0.4064)
			(stroke
				(width 0.1524)
				(type default)
			)
			(layer "B.SilkS")
		)
		(fp_line
			(start 0.7874 -0.4064)
			(end -0.7874 -0.4064)
			(stroke
				(width 0.1524)
				(type default)
			)
			(layer "B.SilkS")
		)
		(fp_line
			(start 0.7874 0.4064)
			(end 0.7874 -0.4064)
			(stroke
				(width 0.1524)
				(type default)
			)
			(layer "B.SilkS")
		)
		(fp_line
			(start -0.67945 -0.3048)
			(end -0.67945 0.3048)
			(stroke
				(width 0.1)
				(type default)
			)
			(layer "B.Fab")
		)
		(fp_line
			(start -0.67945 0.3048)
			(end -0.120396 0.3048)
			(stroke
				(width 0.1)
				(type default)
			)
			(layer "B.Fab")
		)
		(fp_line
			(start -0.12065 -0.3048)
			(end -0.67945 -0.3048)
			(stroke
				(width 0.1)
				(type default)
			)
			(layer "B.Fab")
		)
		(fp_line
			(start -0.12065 -0.2794)
			(end -0.12065 -0.3048)
			(stroke
				(width 0.1)
				(type default)
			)
			(layer "B.Fab")
		)
		(fp_line
			(start -0.120396 0.2794)
			(end 0.12065 0.2794)
			(stroke
				(width 0.1)
				(type default)
			)
			(layer "B.Fab")
		)
		(fp_line
			(start -0.120396 0.3048)
			(end -0.120396 0.2794)
			(stroke
				(width 0.1)
				(type default)
			)
			(layer "B.Fab")
		)
		(fp_line
			(start 0.12065 -0.305054)
			(end 0.12065 -0.2794)
			(stroke
				(width 0.1)
				(type default)
			)
			(layer "B.Fab")
		)
		(fp_line
			(start 0.12065 -0.2794)
			(end -0.12065 -0.2794)
			(stroke
				(width 0.1)
				(type default)
			)
			(layer "B.Fab")
		)
		(fp_line
			(start 0.12065 0.2794)
			(end 0.12065 0.3048)
			(stroke
				(width 0.1)
				(type default)
			)
			(layer "B.Fab")
		)
		(fp_line
			(start 0.12065 0.3048)
			(end 0.67945 0.3048)
			(stroke
				(width 0.1)
				(type default)
			)
			(layer "B.Fab")
		)
		(fp_line
			(start 0.67945 -0.305054)
			(end 0.12065 -0.305054)
			(stroke
				(width 0.1)
				(type default)
			)
			(layer "B.Fab")
		)
		(fp_line
			(start 0.67945 0.3048)
			(end 0.67945 -0.305054)
			(stroke
				(width 0.1)
				(type default)
			)
			(layer "B.Fab")
		)
		(pad "1" smd circle
			(at 0.40005 0 180)
			(size 0 0)
			(layers "B.Cu" "B.Mask" "B.Paste")
			(net "VFG3P3_CLK_GEN")
		)
		(pad "2" smd circle
			(at -0.40005 0 180)
			(size 0 0)
			(layers "B.Cu" "B.Mask" "B.Paste")
			(net "GND")
		)
	)
	(footprint ""
		(layer "B.Cu")
		(at 164.725858 -256.488946 -90)
		(property "Reference" "C482"
			(at 0 0 90)
			(layer "B.SilkS")
			(hide yes)
			(effects
				(font
					(size 1.27 1.27)
				)
				(justify mirror)
			)
		)
		(property "Value" ""
			(at 0 0 90)
			(layer "B.Fab")
			(effects
				(font
					(size 1.27 1.27)
				)
				(justify mirror)
			)
		)
		(duplicate_pad_numbers_are_jumpers no)
		(fp_line
			(start -1.524 0.762)
			(end 1.524 0.762)
			(stroke
				(width 0.1524)
				(type default)
			)
			(layer "B.SilkS")
		)
		(fp_line
			(start 1.524 0.762)
			(end 1.524 -0.762)
			(stroke
				(width 0.1524)
				(type default)
			)
			(layer "B.SilkS")
		)
		(fp_line
			(start -1.524 -0.762)
			(end -1.524 0.762)
			(stroke
				(width 0.1524)
				(type default)
			)
			(layer "B.SilkS")
		)
		(fp_line
			(start 1.524 -0.762)
			(end -1.524 -0.762)
			(stroke
				(width 0.1524)
				(type default)
			)
			(layer "B.SilkS")
		)
		(fp_line
			(start -1.1049 0.724916)
			(end -1.1049 -0.724916)
			(stroke
				(width 0.1)
				(type default)
			)
			(layer "B.Fab")
		)
		(fp_line
			(start 1.1049 0.724916)
			(end -1.1049 0.724916)
			(stroke
				(width 0.1)
				(type default)
			)
			(layer "B.Fab")
		)
		(fp_line
			(start -1.1049 -0.724916)
			(end 1.1049 -0.724916)
			(stroke
				(width 0.1)
				(type default)
			)
			(layer "B.Fab")
		)
		(fp_line
			(start 1.1049 -0.724916)
			(end 1.1049 0.724916)
			(stroke
				(width 0.1)
				(type default)
			)
			(layer "B.Fab")
		)
		(pad "1" smd rect
			(at 0.889 0 270)
			(size 1.016 1.27)
			(layers "B.Cu" "B.Mask" "B.Paste")
			(net "PVCCFA_EHV_FIVRA_CPU1")
		)
		(pad "2" smd rect
			(at -0.889 0 270)
			(size 1.016 1.27)
			(layers "B.Cu" "B.Mask" "B.Paste")
			(net "GND")
		)
	)
	(footprint ""
		(layer "B.Cu")
		(at 367.034572 -184.400952 90)
		(property "Reference" "R2478"
			(at 0 0 90)
			(layer "B.SilkS")
			(hide yes)
			(effects
				(font
					(size 1.27 1.27)
				)
				(justify mirror)
			)
		)
		(property "Value" ""
			(at 0 0 90)
			(layer "B.Fab")
			(effects
				(font
					(size 1.27 1.27)
				)
				(justify mirror)
			)
		)
		(duplicate_pad_numbers_are_jumpers no)
		(fp_line
			(start 0.7874 -0.4064)
			(end -0.7874 -0.4064)
			(stroke
				(width 0.1524)
				(type default)
			)
			(layer "B.SilkS")
		)
		(fp_line
			(start -0.7874 -0.4064)
			(end -0.7874 0.4064)
			(stroke
				(width 0.1524)
				(type default)
			)
			(layer "B.SilkS")
		)
		(fp_line
			(start 0.7874 0.4064)
			(end 0.7874 -0.4064)
			(stroke
				(width 0.1524)
				(type default)
			)
			(layer "B.SilkS")
		)
		(fp_line
			(start -0.7874 0.4064)
			(end 0.7874 0.4064)
			(stroke
				(width 0.1524)
				(type default)
			)
			(layer "B.SilkS")
		)
		(fp_line
			(start 0.67945 -0.305054)
			(end 0.12065 -0.305054)
			(stroke
				(width 0.1)
				(type default)
			)
			(layer "B.Fab")
		)
		(fp_line
			(start 0.12065 -0.305054)
			(end 0.12065 -0.2794)
			(stroke
				(width 0.1)
				(type default)
			)
			(layer "B.Fab")
		)
		(fp_line
			(start -0.12065 -0.3048)
			(end -0.67945 -0.3048)
			(stroke
				(width 0.1)
				(type default)
			)
			(layer "B.Fab")
		)
		(fp_line
			(start -0.67945 -0.3048)
			(end -0.67945 0.3048)
			(stroke
				(width 0.1)
				(type default)
			)
			(layer "B.Fab")
		)
		(fp_line
			(start 0.12065 -0.2794)
			(end -0.12065 -0.2794)
			(stroke
				(width 0.1)
				(type default)
			)
			(layer "B.Fab")
		)
		(fp_line
			(start -0.12065 -0.2794)
			(end -0.12065 -0.3048)
			(stroke
				(width 0.1)
				(type default)
			)
			(layer "B.Fab")
		)
		(fp_line
			(start 0.12065 0.2794)
			(end 0.12065 0.3048)
			(stroke
				(width 0.1)
				(type default)
			)
			(layer "B.Fab")
		)
		(fp_line
			(start -0.120396 0.2794)
			(end 0.12065 0.2794)
			(stroke
				(width 0.1)
				(type default)
			)
			(layer "B.Fab")
		)
		(fp_line
			(start 0.67945 0.3048)
			(end 0.67945 -0.305054)
			(stroke
				(width 0.1)
				(type default)
			)
			(layer "B.Fab")
		)
		(fp_line
			(start 0.12065 0.3048)
			(end 0.67945 0.3048)
			(stroke
				(width 0.1)
				(type default)
			)
			(layer "B.Fab")
		)
		(fp_line
			(start -0.120396 0.3048)
			(end -0.120396 0.2794)
			(stroke
				(width 0.1)
				(type default)
			)
			(layer "B.Fab")
		)
		(fp_line
			(start -0.67945 0.3048)
			(end -0.120396 0.3048)
			(stroke
				(width 0.1)
				(type default)
			)
			(layer "B.Fab")
		)
		(pad "1" smd circle
			(at 0.40005 0 270)
			(size 0 0)
			(layers "B.Cu" "B.Mask" "B.Paste")
			(net "SMB_PEHPCPU0_LVC3_SDA_R0")
		)
		(pad "2" smd circle
			(at -0.40005 0 270)
			(size 0 0)
			(layers "B.Cu" "B.Mask" "B.Paste")
			(net "SMB_PEHPCPU0_LVC3_SDA")
		)
	)
	(footprint ""
		(layer "B.Cu")
		(at 435.549802 -12.104116 180)
		(property "Reference" "C1238"
			(at 0 0 0)
			(layer "B.SilkS")
			(hide yes)
			(effects
				(font
					(size 1.27 1.27)
				)
				(justify mirror)
			)
		)
		(property "Value" ""
			(at 0 0 0)
			(layer "B.Fab")
			(effects
				(font
					(size 1.27 1.27)
				)
				(justify mirror)
			)
		)
		(duplicate_pad_numbers_are_jumpers no)
		(fp_line
			(start 0.7874 0.4064)
			(end 0.7874 -0.4064)
			(stroke
				(width 0.1524)
				(type default)
			)
			(layer "B.SilkS")
		)
		(fp_line
			(start 0.7874 -0.4064)
			(end -0.7874 -0.4064)
			(stroke
				(width 0.1524)
				(type default)
			)
			(layer "B.SilkS")
		)
		(fp_line
			(start -0.7874 0.4064)
			(end 0.7874 0.4064)
			(stroke
				(width 0.1524)
				(type default)
			)
			(layer "B.SilkS")
		)
		(fp_line
			(start -0.7874 -0.4064)
			(end -0.7874 0.4064)
			(stroke
				(width 0.1524)
				(type default)
			)
			(layer "B.SilkS")
		)
		(fp_line
			(start 0.67945 0.3048)
			(end 0.67945 -0.305054)
			(stroke
				(width 0.1)
				(type default)
			)
			(layer "B.Fab")
		)
		(fp_line
			(start 0.67945 -0.305054)
			(end 0.12065 -0.305054)
			(stroke
				(width 0.1)
				(type default)
			)
			(layer "B.Fab")
		)
		(fp_line
			(start 0.12065 0.3048)
			(end 0.67945 0.3048)
			(stroke
				(width 0.1)
				(type default)
			)
			(layer "B.Fab")
		)
		(fp_line
			(start 0.12065 0.2794)
			(end 0.12065 0.3048)
			(stroke
				(width 0.1)
				(type default)
			)
			(layer "B.Fab")
		)
		(fp_line
			(start 0.12065 -0.2794)
			(end -0.12065 -0.2794)
			(stroke
				(width 0.1)
				(type default)
			)
			(layer "B.Fab")
		)
		(fp_line
			(start 0.12065 -0.305054)
			(end 0.12065 -0.2794)
			(stroke
				(width 0.1)
				(type default)
			)
			(layer "B.Fab")
		)
		(fp_line
			(start -0.120396 0.3048)
			(end -0.120396 0.2794)
			(stroke
				(width 0.1)
				(type default)
			)
			(layer "B.Fab")
		)
		(fp_line
			(start -0.120396 0.2794)
			(end 0.12065 0.2794)
			(stroke
				(width 0.1)
				(type default)
			)
			(layer "B.Fab")
		)
		(fp_line
			(start -0.12065 -0.2794)
			(end -0.12065 -0.3048)
			(stroke
				(width 0.1)
				(type default)
			)
			(layer "B.Fab")
		)
		(fp_line
			(start -0.12065 -0.3048)
			(end -0.67945 -0.3048)
			(stroke
				(width 0.1)
				(type default)
			)
			(layer "B.Fab")
		)
		(fp_line
			(start -0.67945 0.3048)
			(end -0.120396 0.3048)
			(stroke
				(width 0.1)
				(type default)
			)
			(layer "B.Fab")
		)
		(fp_line
			(start -0.67945 -0.3048)
			(end -0.67945 0.3048)
			(stroke
				(width 0.1)
				(type default)
			)
			(layer "B.Fab")
		)
		(pad "1" smd circle
			(at 0.40005 0)
			(size 0 0)
			(layers "B.Cu" "B.Mask" "B.Paste")
			(net "P3V3_OCP_SFF")
		)
		(pad "2" smd circle
			(at -0.40005 0)
			(size 0 0)
			(layers "B.Cu" "B.Mask" "B.Paste")
			(net "GND")
		)
	)
)
